#ISCELL
  mstr_misc dns *
  *
#ISCELL
  mstr_symbols intel_corp_bpage *
  *
#CELL
  mstr_ttl ttl1g126_a *
  page200_i103
#ISCELL
  mstr_symbols agnd0 *
  page200_i106
#CELL
  mstr_discrete res *
  page200_i108
#ISCELL
  mstr_symbols p12v_stby *
  page200_i109
#ISCELL
  mstr_symbols gnd *
  page200_i114
#ISCELL
  mstr_standard offpage *
  page200_i118
#ISCELL
  mstr_standard offpage *
  page200_i121
#ISCELL
  mstr_standard offpage *
  page200_i134
#ISCELL
  mstr_standard offpage *
  page200_i135
#ISCELL
  mstr_symbols p12v_stby *
  page200_i144
#ISCELL
  mstr_symbols agnd0 *
  page200_i147
#CELL
  mstr_discrete res *
  page200_i149
#ISCELL
  mstr_symbols p3v3_stby *
  page200_i150
#ISCELL
  mstr_standard offpage *
  page200_i153
#CELL
  mstr_discrete res *
  page200_i154
#CELL
  mstr_discrete cap *
  page200_i155
#ISCELL
  mstr_symbols gnd *
  page200_i156
#ISCELL
  mstr_symbols p3v3_stby *
  page200_i157
#CELL
  mstr_discrete res *
  page200_i158
#CELL
  mstr_vreg tps3700 *
  page200_i163
#CELL
  mstr_vreg tps3700 *
  page200_i170
#CELL
  mstr_discrete res *
  page200_i174
#CELL
  mstr_discrete res *
  page200_i175
#ISCELL
  mstr_symbols gnd *
  page200_i178
#ISCELL
  mstr_symbols gnd *
  page200_i179
#ISCELL
  mstr_symbols agnd0 *
  page200_i180
#ISCELL
  mstr_symbols agnd0 *
  page200_i181
#ISCELL
  mstr_symbols gnd *
  page200_i183
#ISCELL
  mstr_symbols p12v_stby *
  page200_i184
#CELL
  dev_discrete cap_a *
  page200_i185
#ISCELL
  mstr_symbols agnd0 *
  page200_i186
#CELL
  dev_discrete cap_a *
  page200_i187
#ISCELL
  mstr_symbols agnd0 *
  page200_i188
#ISCELL
  mstr_symbols p3v3_stby *
  page200_i190
#CELL
  mstr_discrete res *
  page200_i191
#CELL
  mstr_discrete res *
  page200_i192
#ISCELL
  mstr_symbols p3v3_stby *
  page200_i194
#CELL
  mstr_discrete fet_n_dual *
  page200_i196
#ISCELL
  mstr_symbols gnd *
  page200_i197
#CELL
  mstr_discrete fet_n_dual *
  page200_i199
#CELL
  mstr_vreg tps3700 *
  page200_i200
#CELL
  dev_discrete cap_a *
  page200_i201
#ISCELL
  mstr_symbols gnd *
  page200_i202
#CELL
  mstr_discrete fet_n *
  page200_i203
#CELL
  mstr_discrete res *
  page200_i204
#ISCELL
  mstr_symbols p3v3_stby *
  page200_i205
#ISCELL
  mstr_symbols gnd *
  page200_i206
#ISCELL
  mstr_standard offpage *
  page200_i207
#CELL
  mstr_discrete res *
  page200_i210
#ISCELL
  mstr_symbols p3v3_stby *
  page200_i211
#CELL
  mstr_discrete diode *
  page200_i213
#CELL
  mstr_discrete diode *
  page200_i214
#CELL
  mstr_discrete res *
  page200_i215
#ISCELL
  mstr_symbols p3v3_stby *
  page200_i216
#ISCELL
  mstr_symbols agnd0 *
  page200_i217
#CELL
  mstr_discrete res *
  page200_i218
#ISCELL
  mstr_symbols agnd0 *
  page200_i219
#CELL
  mstr_discrete diode *
  page200_i220
#ISCELL
  mstr_symbols gnd *
  page200_i221
#CELL
  mstr_discrete res *
  page200_i222
#ISCELL
  mstr_symbols p12v_stby *
  page200_i223
#ISCELL
  mstr_standard offpage *
  page200_i224
#CELL
  mstr_discrete fet_n *
  page200_i225
#ISCELL
  mstr_standard offpage *
  page200_i226
#ISCELL
  mstr_symbols gnd *
  page200_i227
#CELL
  w_hdl sc22p50v2jn-4gp *
  page200_i235
#CELL
  w_hdl sc22p50v2jn-4gp *
  page200_i236
#ISCELL
  mstr_symbols agnd0 *
  page200_i237
#ISCELL
  mstr_symbols agnd0 *
  page200_i238
#ISCELL
  mstr_standard offpage *
  page200_i241
#CELL
  mstr_discrete res *
  page200_i243
#CELL
  mstr_discrete res *
  page200_i244
#CELL
  mstr_discrete res *
  page200_i246
#CELL
  w_hdl 270kr2f-gp *
  page200_i249
#CELL
  w_hdl 232kr2f-2-gp *
  page200_i250
#CELL
  mstr_discrete res *
  page200_i251
#CELL
  mstr_discrete res *
  page200_i252
#CELL
  mstr_discrete res *
  page200_i253
#CELL
  dev_discrete cap_a *
  page200_i36
#ISCELL
  mstr_standard offpage *
  page200_i37
#ISCELL
  mstr_standard offpage *
  page200_i38
#ISCELL
  mstr_symbols agnd0 *
  page200_i39
#CELL
  dev_discrete cap_a *
  page200_i40
#ISCELL
  mstr_symbols agnd0 *
  page200_i41
#CELL
  dev_discrete cap_a *
  page200_i42
#CELL
  mstr_discrete res *
  page200_i43
#CELL
  mstr_discrete res *
  page200_i44
#ISCELL
  mstr_standard offpage *
  page200_i45
#ISCELL
  mstr_standard offpage *
  page200_i46
#CELL
  mstr_discrete res *
  page200_i47
#CELL
  mstr_discrete res *
  page200_i48
#CELL
  mstr_discrete res_pwr *
  page200_i49
#CELL
  mstr_discrete res_pwr *
  page200_i50
#CELL
  mstr_discrete res *
  page200_i51
#CELL
  mstr_discrete res *
  page200_i52
#ISCELL
  mstr_symbols p12v_psu *
  page200_i53
#CELL
  mstr_discrete mosfetn_1d3s *
  page200_i54
#ISCELL
  mstr_standard offpage *
  page200_i55
#CELL
  mstr_discrete res *
  page200_i56
#CELL
  mstr_discrete mosfetn_1d3s *
  page200_i57
#CELL
  mstr_discrete res *
  page200_i58
#CELL
  mstr_discrete mosfetn_1d3s *
  page200_i59
#CELL
  mstr_discrete res *
  page200_i60
#ISCELL
  mstr_symbols p12v_stby *
  page200_i64
#CELL
  mstr_discrete res *
  page200_i70
#CELL
  mstr_discrete res *
  page200_i71
#ISCELL
  mstr_standard offpage *
  page200_i72
#ISCELL
  mstr_symbols p3v3_stby *
  page200_i78
#CELL
  mstr_discrete res *
  page200_i86
#ISCELL
  mstr_standard offpage *
  page200_i92
#ISCELL
  mstr_standard offpage *
  page200_i94
